# SCM (Grand Teton) — schematic netlist excerpt (pin names and nets, part order shuffled) for the footprints in the layout excerpt that follows; sources: Cadence DE-HDL packaged netlist, KiCad conversion of 12092022_DA0F0TMDCD0_F0T_Management_Board_D_brd_V3_OCP.brd

R388  Q_RES  33.2 1% CHIP  pkg 0402LF  page 22 : A = RST_SRST_PLD_BMC_R_N ; B = RST_SRST_PLD_BMC_R1_N
PR496  Q_RES  150K 1% CHIP  pkg 0402LF  page 55 : A = P1V2_AUX_MODE ; B = GND

(kicad_pcb
	(version 20260206)
	(generator "pcbnew")
	(generator_version "10.0")
	(general
		(thickness 1.6)
		(legacy_teardrops no)
	)
	(paper "A4")
	(title_block
		(title "12092022_DA0F0TMDCD0_F0T_Management_Board_D_brd_V3_OCP.brd")
		(comment 1 "Grand Teton / footprints 714-715 of 1440")
	)
	(layers
		(0 "F.Cu" signal "TOP")
		(4 "In1.Cu" signal "GND")
		(6 "In2.Cu" signal "IN1")
		(8 "In3.Cu" signal "GND1")
		(10 "In4.Cu" signal "IN2")
		(12 "In5.Cu" signal "VCC")
		(14 "In6.Cu" signal "VCC1")
		(16 "In7.Cu" signal "IN3")
		(18 "In8.Cu" signal "GND2")
		(20 "In9.Cu" signal "IN4")
		(22 "In10.Cu" signal "GND3")
		(2 "B.Cu" signal "BOTTOM")
		(9 "F.Adhes" user "F.Adhesive")
		(11 "B.Adhes" user "B.Adhesive")
		(13 "F.Paste" user "Package Geometry/Pastemask Top")
		(15 "B.Paste" user "Package Geometry/Pastemask Bottom")
		(5 "F.SilkS" user "Ref Des/Silkscreen Top")
		(7 "B.SilkS" user "Ref Des/Silkscreen Bottom")
		(1 "F.Mask" user "Board Geometry/Soldermask Top")
		(3 "B.Mask" user "Board Geometry/Soldermask Bottom")
		(17 "Dwgs.User" user "User.Drawings")
		(19 "Cmts.User" user "User.Comments")
		(21 "Eco1.User" user "User.Eco1")
		(23 "Eco2.User" user "User.Eco2")
		(25 "Edge.Cuts" user "Board Geometry/Outline")
		(27 "Margin" user)
		(31 "F.CrtYd" user "Package Geometry/Place Bound Top")
		(29 "B.CrtYd" user "Package Geometry/Place Bound Bottom")
		(35 "F.Fab" user "Ref Des/Assembly Top")
		(33 "B.Fab" user "Ref Des/Assembly Bottom")
	)
	(footprint ""
		(layer "F.Cu")
		(at 77.947774 -69.407024 180)
		(property "Reference" "PR496"
			(at 0 0 180)
			(layer "F.SilkS")
			(hide yes)
			(effects
				(font
					(size 1.27 1.27)
				)
			)
		)
		(property "Value" ""
			(at 0 0 180)
			(layer "F.Fab")
			(effects
				(font
					(size 1.27 1.27)
				)
			)
		)
		(duplicate_pad_numbers_are_jumpers no)
		(fp_line
			(start 0.7874 0.4064)
			(end -0.7874 0.4064)
			(stroke
				(width 0.1524)
				(type default)
			)
			(layer "F.SilkS")
		)
		(fp_line
			(start 0.7874 -0.4064)
			(end 0.7874 0.4064)
			(stroke
				(width 0.1524)
				(type default)
			)
			(layer "F.SilkS")
		)
		(fp_line
			(start -0.7874 0.4064)
			(end -0.7874 -0.4064)
			(stroke
				(width 0.1524)
				(type default)
			)
			(layer "F.SilkS")
		)
		(fp_line
			(start -0.7874 -0.4064)
			(end 0.7874 -0.4064)
			(stroke
				(width 0.1524)
				(type default)
			)
			(layer "F.SilkS")
		)
		(fp_line
			(start 0.67945 0.3048)
			(end 0.120396 0.3048)
			(stroke
				(width 0.1)
				(type default)
			)
			(layer "F.Fab")
		)
		(fp_line
			(start 0.67945 -0.3048)
			(end 0.67945 0.3048)
			(stroke
				(width 0.1)
				(type default)
			)
			(layer "F.Fab")
		)
		(fp_line
			(start 0.12065 -0.2794)
			(end 0.12065 -0.3048)
			(stroke
				(width 0.1)
				(type default)
			)
			(layer "F.Fab")
		)
		(fp_line
			(start 0.12065 -0.3048)
			(end 0.67945 -0.3048)
			(stroke
				(width 0.1)
				(type default)
			)
			(layer "F.Fab")
		)
		(fp_line
			(start 0.120396 0.3048)
			(end 0.120396 0.2794)
			(stroke
				(width 0.1)
				(type default)
			)
			(layer "F.Fab")
		)
		(fp_line
			(start 0.120396 0.2794)
			(end -0.12065 0.2794)
			(stroke
				(width 0.1)
				(type default)
			)
			(layer "F.Fab")
		)
		(fp_line
			(start -0.12065 0.3048)
			(end -0.67945 0.3048)
			(stroke
				(width 0.1)
				(type default)
			)
			(layer "F.Fab")
		)
		(fp_line
			(start -0.12065 0.2794)
			(end -0.12065 0.3048)
			(stroke
				(width 0.1)
				(type default)
			)
			(layer "F.Fab")
		)
		(fp_line
			(start -0.12065 -0.2794)
			(end 0.12065 -0.2794)
			(stroke
				(width 0.1)
				(type default)
			)
			(layer "F.Fab")
		)
		(fp_line
			(start -0.12065 -0.305054)
			(end -0.12065 -0.2794)
			(stroke
				(width 0.1)
				(type default)
			)
			(layer "F.Fab")
		)
		(fp_line
			(start -0.67945 0.3048)
			(end -0.67945 -0.305054)
			(stroke
				(width 0.1)
				(type default)
			)
			(layer "F.Fab")
		)
		(fp_line
			(start -0.67945 -0.305054)
			(end -0.12065 -0.305054)
			(stroke
				(width 0.1)
				(type default)
			)
			(layer "F.Fab")
		)
		(pad "1" smd circle
			(at -0.40005 0 180)
			(size 0 0)
			(layers "F.Cu" "F.Mask" "F.Paste")
			(net "P1V2_AUX_MODE")
		)
		(pad "2" smd circle
			(at 0.40005 0 180)
			(size 0 0)
			(layers "F.Cu" "F.Mask" "F.Paste")
			(net "GND")
		)
	)
	(footprint ""
		(layer "F.Cu")
		(at 4.318 -80.899 -90)
		(property "Reference" "R388"
			(at 0 0 270)
			(layer "F.SilkS")
			(hide yes)
			(effects
				(font
					(size 1.27 1.27)
				)
			)
		)
		(property "Value" ""
			(at 0 0 270)
			(layer "F.Fab")
			(effects
				(font
					(size 1.27 1.27)
				)
			)
		)
		(duplicate_pad_numbers_are_jumpers no)
		(fp_line
			(start -0.7874 0.4064)
			(end -0.7874 -0.4064)
			(stroke
				(width 0.1524)
				(type default)
			)
			(layer "F.SilkS")
		)
		(fp_line
			(start 0.7874 0.4064)
			(end -0.7874 0.4064)
			(stroke
				(width 0.1524)
				(type default)
			)
			(layer "F.SilkS")
		)
		(fp_line
			(start -0.7874 -0.4064)
			(end 0.7874 -0.4064)
			(stroke
				(width 0.1524)
				(type default)
			)
			(layer "F.SilkS")
		)
		(fp_line
			(start 0.7874 -0.4064)
			(end 0.7874 0.4064)
			(stroke
				(width 0.1524)
				(type default)
			)
			(layer "F.SilkS")
		)
		(fp_line
			(start -0.67945 0.3048)
			(end -0.67945 -0.305054)
			(stroke
				(width 0.1)
				(type default)
			)
			(layer "F.Fab")
		)
		(fp_line
			(start -0.12065 0.3048)
			(end -0.67945 0.3048)
			(stroke
				(width 0.1)
				(type default)
			)
			(layer "F.Fab")
		)
		(fp_line
			(start 0.120396 0.3048)
			(end 0.120396 0.2794)
			(stroke
				(width 0.1)
				(type default)
			)
			(layer "F.Fab")
		)
		(fp_line
			(start 0.67945 0.3048)
			(end 0.120396 0.3048)
			(stroke
				(width 0.1)
				(type default)
			)
			(layer "F.Fab")
		)
		(fp_line
			(start -0.12065 0.2794)
			(end -0.12065 0.3048)
			(stroke
				(width 0.1)
				(type default)
			)
			(layer "F.Fab")
		)
		(fp_line
			(start 0.120396 0.2794)
			(end -0.12065 0.2794)
			(stroke
				(width 0.1)
				(type default)
			)
			(layer "F.Fab")
		)
		(fp_line
			(start -0.12065 -0.2794)
			(end 0.12065 -0.2794)
			(stroke
				(width 0.1)
				(type default)
			)
			(layer "F.Fab")
		)
		(fp_line
			(start 0.12065 -0.2794)
			(end 0.12065 -0.3048)
			(stroke
				(width 0.1)
				(type default)
			)
			(layer "F.Fab")
		)
		(fp_line
			(start 0.12065 -0.3048)
			(end 0.67945 -0.3048)
			(stroke
				(width 0.1)
				(type default)
			)
			(layer "F.Fab")
		)
		(fp_line
			(start 0.67945 -0.3048)
			(end 0.67945 0.3048)
			(stroke
				(width 0.1)
				(type default)
			)
			(layer "F.Fab")
		)
		(fp_line
			(start -0.67945 -0.305054)
			(end -0.12065 -0.305054)
			(stroke
				(width 0.1)
				(type default)
			)
			(layer "F.Fab")
		)
		(fp_line
			(start -0.12065 -0.305054)
			(end -0.12065 -0.2794)
			(stroke
				(width 0.1)
				(type default)
			)
			(layer "F.Fab")
		)
		(pad "1" smd circle
			(at -0.40005 0 270)
			(size 0 0)
			(layers "F.Cu" "F.Mask" "F.Paste")
			(net "RST_SRST_PLD_BMC_R_N")
		)
		(pad "2" smd circle
			(at 0.40005 0 270)
			(size 0 0)
			(layers "F.Cu" "F.Mask" "F.Paste")
			(net "RST_SRST_PLD_BMC_R1_N")
		)
	)
)
